(kicad_pcb
	(version 20260206)
	(generator "pcbnew")
	(generator_version "10.0")
	(general
		(thickness 1.6)
		(legacy_teardrops no)
	)
	(paper "A4")
	(title_block
		(title "dpb — 14545-sa.0730WZS0815.brd")
		(comment 1 "Honey Badger (Wiwynn) / footprints 864-871 of 1066")
	)
	(layers
		(0 "F.Cu" signal "TOP")
		(4 "In1.Cu" signal "L2GND")
		(6 "In2.Cu" signal "L3")
		(8 "In3.Cu" signal "L4VCC")
		(10 "In4.Cu" signal "L5VCC")
		(12 "In5.Cu" signal "L6")
		(14 "In6.Cu" signal "L7GND")
		(2 "B.Cu" signal "BOTTOM")
		(9 "F.Adhes" user "F.Adhesive")
		(11 "B.Adhes" user "B.Adhesive")
		(13 "F.Paste" user "Package Geometry/Pastemask Top")
		(15 "B.Paste" user "Package Geometry/Pastemask Bottom")
		(5 "F.SilkS" user "Ref Des/Silkscreen Top")
		(7 "B.SilkS" user "Ref Des/Silkscreen Bottom")
		(1 "F.Mask" user "Board Geometry/Soldermask Top")
		(3 "B.Mask" user "Board Geometry/Soldermask Bottom")
		(17 "Dwgs.User" user "User.Drawings")
		(19 "Cmts.User" user "User.Comments")
		(21 "Eco1.User" user "User.Eco1")
		(23 "Eco2.User" user "User.Eco2")
		(25 "Edge.Cuts" user "Board Geometry/Outline")
		(27 "Margin" user)
		(31 "F.CrtYd" user "Package Geometry/Place Bound Top")
		(29 "B.CrtYd" user "Package Geometry/Place Bound Bottom")
		(35 "F.Fab" user "Ref Des/Assembly Top")
		(33 "B.Fab" user "Ref Des/Assembly Bottom")
	)
	(footprint ""
		(layer "F.Cu")
		(at 36.575746 -18.1737 180)
		(property "Reference" "PL4"
			(at 0 0 180)
			(layer "F.SilkS")
			(hide yes)
			(effects
				(font
					(size 1.27 1.27)
				)
			)
		)
		(property "Value" "IND-4D7UH-291-GP"
			(at -6.34492 -3.502152 180)
			(unlocked yes)
			(layer "F.Fab")
			(hide yes)
			(effects
				(font
					(size 1.016 1.016)
					(thickness 0.1524)
				)
			)
		)
		(property "Device Type" "L11102530H158"
			(at -6.3246 -5.08 180)
			(unlocked yes)
			(layer "F.Fab")
			(hide yes)
			(effects
				(font
					(size 1.016 1.016)
					(thickness 0.1524)
				)
			)
		)
		(duplicate_pad_numbers_are_jumpers no)
		(fp_line
			(start 5.2578 6.3754)
			(end 5.2578 -6.3754)
			(stroke
				(width 0.1524)
				(type default)
			)
			(layer "F.SilkS")
		)
		(fp_line
			(start 5.2578 -6.3754)
			(end -5.2578 -6.3754)
			(stroke
				(width 0.1524)
				(type default)
			)
			(layer "F.SilkS")
		)
		(fp_line
			(start -5.2578 6.3754)
			(end 5.2578 6.3754)
			(stroke
				(width 0.1524)
				(type default)
			)
			(layer "F.SilkS")
		)
		(fp_line
			(start -5.2578 -6.3754)
			(end -5.2578 6.3754)
			(stroke
				(width 0.1524)
				(type default)
			)
			(layer "F.SilkS")
		)
		(fp_rect
			(start -5.0038 5.4991)
			(end 5.0038 -5.4991)
			(stroke
				(width 0)
				(type default)
			)
			(fill no)
			(layer "F.CrtYd")
		)
		(fp_poly
			(pts
				(xy -5.5118 6.4516) (xy -5.5118 -6.4516) (xy 5.5118 -6.4516) (xy 5.5118 -0.8509) (xy 5.0038 -0.8509)
				(xy 5.0038 -5.4991) (xy -5.0038 -5.4991) (xy -5.0038 5.4991) (xy 5.0038 5.4991) (xy 5.0038 -0.8382)
				(xy 5.5118 -0.8382) (xy 5.5118 6.4516)
			)
			(stroke
				(width 0)
				(type default)
			)
			(fill no)
			(layer "F.CrtYd")
		)
		(fp_rect
			(start -5.5118 6.4516)
			(end 5.5118 -6.4516)
			(stroke
				(width 0)
				(type default)
			)
			(fill no)
			(layer "F.Fab")
		)
		(pad "1" smd rect
			(at 0 -4.435094 180)
			(size 3.2512 3.3782)
			(layers "F.Cu" "F.Mask" "F.Paste")
			(net "P5VB_LL")
		)
		(pad "2" smd rect
			(at 0 4.435094 180)
			(size 3.2512 3.3782)
			(layers "F.Cu" "F.Mask" "F.Paste")
			(net "P5VB")
		)
	)
	(footprint ""
		(layer "F.Cu")
		(at 30.860746 -343.4207 90)
		(property "Reference" "R256"
			(at 0 0 90)
			(layer "F.SilkS")
			(hide yes)
			(effects
				(font
					(size 1.27 1.27)
				)
			)
		)
		(property "Value" "0R2J-2-GP"
			(at 0.064008 -3.993896 90)
			(unlocked yes)
			(layer "F.Fab")
			(hide yes)
			(effects
				(font
					(size 1.016 1.016)
					(thickness 0.1524)
				)
			)
		)
		(property "Device Type" "R402H16"
			(at 0.064008 -5.517896 90)
			(unlocked yes)
			(layer "F.Fab")
			(hide yes)
			(effects
				(font
					(size 1.016 1.016)
					(thickness 0.1524)
				)
			)
		)
		(duplicate_pad_numbers_are_jumpers no)
		(fp_line
			(start 0.508 -0.9398)
			(end -0.508 -0.9398)
			(stroke
				(width 0.1524)
				(type default)
			)
			(layer "F.SilkS")
		)
		(fp_line
			(start -0.508 -0.9398)
			(end -0.508 0.9398)
			(stroke
				(width 0.1524)
				(type default)
			)
			(layer "F.SilkS")
		)
		(fp_rect
			(start -0.508 0.9398)
			(end 0.508 -0.9398)
			(stroke
				(width 0)
				(type default)
			)
			(fill no)
			(layer "F.CrtYd")
		)
		(fp_rect
			(start -0.508 0.9398)
			(end 0.508 -0.9398)
			(stroke
				(width 0)
				(type default)
			)
			(fill no)
			(layer "F.Fab")
		)
		(pad "1" smd custom
			(at 0 -0.4445 90)
			(size 0.1397 0.1397)
			(layers "F.Cu" "F.Mask" "F.Paste")
			(net "DRV_ACT_NET11")
			(options
				(clearance outline)
				(anchor circle)
			)
			(primitives
				(gr_poly
					(pts
						(arc
							(start -0.1778 -0.2794)
							(mid -0.249642 -0.249642)
							(end -0.2794 -0.1778)
						)
						(arc
							(start -0.2794 0.1778)
							(mid -0.249642 0.249642)
							(end -0.1778 0.2794)
						)
						(arc
							(start 0.1778 0.2794)
							(mid 0.249642 0.249642)
							(end 0.2794 0.1778)
						)
						(arc
							(start 0.2794 -0.1778)
							(mid 0.249642 -0.249642)
							(end 0.1778 -0.2794)
						)
					)
					(width 0)
					(fill yes)
				)
			)
		)
		(pad "2" smd custom
			(at 0 0.4445 90)
			(size 0.1397 0.1397)
			(layers "F.Cu" "F.Mask" "F.Paste")
			(net "DRIVE_ACT_11")
			(options
				(clearance outline)
				(anchor circle)
			)
			(primitives
				(gr_poly
					(pts
						(arc
							(start -0.1778 -0.2794)
							(mid -0.249642 -0.249642)
							(end -0.2794 -0.1778)
						)
						(arc
							(start -0.2794 0.1778)
							(mid -0.249642 0.249642)
							(end -0.1778 0.2794)
						)
						(arc
							(start 0.1778 0.2794)
							(mid 0.249642 0.249642)
							(end 0.2794 0.1778)
						)
						(arc
							(start 0.2794 -0.1778)
							(mid 0.249642 -0.249642)
							(end 0.1778 -0.2794)
						)
					)
					(width 0)
					(fill yes)
				)
			)
		)
	)
	(footprint ""
		(layer "F.Cu")
		(at 219.201746 -19.6977 180)
		(property "Reference" "PL2"
			(at 0 0 180)
			(layer "F.SilkS")
			(hide yes)
			(effects
				(font
					(size 1.27 1.27)
				)
			)
		)
		(property "Value" "IND-4D7UH-291-GP"
			(at -6.34492 -3.502152 180)
			(unlocked yes)
			(layer "F.Fab")
			(hide yes)
			(effects
				(font
					(size 1.016 1.016)
					(thickness 0.1524)
				)
			)
		)
		(property "Device Type" "L11102530H158"
			(at -6.3246 -5.08 180)
			(unlocked yes)
			(layer "F.Fab")
			(hide yes)
			(effects
				(font
					(size 1.016 1.016)
					(thickness 0.1524)
				)
			)
		)
		(duplicate_pad_numbers_are_jumpers no)
		(fp_line
			(start 5.2578 6.3754)
			(end 5.2578 -6.3754)
			(stroke
				(width 0.1524)
				(type default)
			)
			(layer "F.SilkS")
		)
		(fp_line
			(start 5.2578 -6.3754)
			(end -5.2578 -6.3754)
			(stroke
				(width 0.1524)
				(type default)
			)
			(layer "F.SilkS")
		)
		(fp_line
			(start -5.2578 6.3754)
			(end 5.2578 6.3754)
			(stroke
				(width 0.1524)
				(type default)
			)
			(layer "F.SilkS")
		)
		(fp_line
			(start -5.2578 -6.3754)
			(end -5.2578 6.3754)
			(stroke
				(width 0.1524)
				(type default)
			)
			(layer "F.SilkS")
		)
		(fp_rect
			(start -5.0038 5.4991)
			(end 5.0038 -5.4991)
			(stroke
				(width 0)
				(type default)
			)
			(fill no)
			(layer "F.CrtYd")
		)
		(fp_poly
			(pts
				(xy -5.5118 6.4516) (xy -5.5118 -6.4516) (xy 5.5118 -6.4516) (xy 5.5118 -0.8509) (xy 5.0038 -0.8509)
				(xy 5.0038 -5.4991) (xy -5.0038 -5.4991) (xy -5.0038 5.4991) (xy 5.0038 5.4991) (xy 5.0038 -0.8382)
				(xy 5.5118 -0.8382) (xy 5.5118 6.4516)
			)
			(stroke
				(width 0)
				(type default)
			)
			(fill no)
			(layer "F.CrtYd")
		)
		(fp_rect
			(start -5.5118 6.4516)
			(end 5.5118 -6.4516)
			(stroke
				(width 0)
				(type default)
			)
			(fill no)
			(layer "F.Fab")
		)
		(pad "1" smd rect
			(at 0 -4.435094 180)
			(size 3.2512 3.3782)
			(layers "F.Cu" "F.Mask" "F.Paste")
			(net "P5VA_LL")
		)
		(pad "2" smd rect
			(at 0 4.435094 180)
			(size 3.2512 3.3782)
			(layers "F.Cu" "F.Mask" "F.Paste")
			(net "P5VA")
		)
	)
	(footprint ""
		(layer "F.Cu")
		(at 10.5156 -151.7396 90)
		(property "Reference" "R544"
			(at 0 0 90)
			(layer "F.SilkS")
			(hide yes)
			(effects
				(font
					(size 1.27 1.27)
				)
			)
		)
		(property "Value" "0R2J-2-GP"
			(at 0.064008 -3.993896 90)
			(unlocked yes)
			(layer "F.Fab")
			(hide yes)
			(effects
				(font
					(size 1.016 1.016)
					(thickness 0.1524)
				)
			)
		)
		(property "Device Type" "R402H16"
			(at 0.064008 -5.517896 90)
			(unlocked yes)
			(layer "F.Fab")
			(hide yes)
			(effects
				(font
					(size 1.016 1.016)
					(thickness 0.1524)
				)
			)
		)
		(duplicate_pad_numbers_are_jumpers no)
		(fp_line
			(start 0.508 -0.9398)
			(end -0.508 -0.9398)
			(stroke
				(width 0.1524)
				(type default)
			)
			(layer "F.SilkS")
		)
		(fp_line
			(start -0.508 -0.9398)
			(end -0.508 0.9398)
			(stroke
				(width 0.1524)
				(type default)
			)
			(layer "F.SilkS")
		)
		(fp_rect
			(start -0.508 0.9398)
			(end 0.508 -0.9398)
			(stroke
				(width 0)
				(type default)
			)
			(fill no)
			(layer "F.CrtYd")
		)
		(fp_rect
			(start -0.508 0.9398)
			(end 0.508 -0.9398)
			(stroke
				(width 0)
				(type default)
			)
			(fill no)
			(layer "F.Fab")
		)
		(pad "1" smd custom
			(at 0 -0.4445 90)
			(size 0.1397 0.1397)
			(layers "F.Cu" "F.Mask" "F.Paste")
			(net "I2C_B_SCL_DAMP_B")
			(options
				(clearance outline)
				(anchor circle)
			)
			(primitives
				(gr_poly
					(pts
						(arc
							(start -0.1778 -0.2794)
							(mid -0.249642 -0.249642)
							(end -0.2794 -0.1778)
						)
						(arc
							(start -0.2794 0.1778)
							(mid -0.249642 0.249642)
							(end -0.1778 0.2794)
						)
						(arc
							(start 0.1778 0.2794)
							(mid 0.249642 0.249642)
							(end 0.2794 0.1778)
						)
						(arc
							(start 0.2794 -0.1778)
							(mid 0.249642 -0.249642)
							(end 0.1778 -0.2794)
						)
					)
					(width 0)
					(fill yes)
				)
			)
		)
		(pad "2" smd custom
			(at 0 0.4445 90)
			(size 0.1397 0.1397)
			(layers "F.Cu" "F.Mask" "F.Paste")
			(net "I2C_B_SCL")
			(options
				(clearance outline)
				(anchor circle)
			)
			(primitives
				(gr_poly
					(pts
						(arc
							(start -0.1778 -0.2794)
							(mid -0.249642 -0.249642)
							(end -0.2794 -0.1778)
						)
						(arc
							(start -0.2794 0.1778)
							(mid -0.249642 0.249642)
							(end -0.1778 0.2794)
						)
						(arc
							(start 0.1778 0.2794)
							(mid 0.249642 0.249642)
							(end 0.2794 0.1778)
						)
						(arc
							(start 0.2794 -0.1778)
							(mid 0.249642 -0.249642)
							(end 0.1778 -0.2794)
						)
					)
					(width 0)
					(fill yes)
				)
			)
		)
	)
	(footprint ""
		(layer "F.Cu")
		(at 188.988446 -456.472036)
		(property "Reference" "R350"
			(at 0 0 0)
			(layer "F.SilkS")
			(hide yes)
			(effects
				(font
					(size 1.27 1.27)
				)
			)
		)
		(property "Value" "4K7R2J-2-GP"
			(at 0.064008 -3.993896 0)
			(unlocked yes)
			(layer "F.Fab")
			(hide yes)
			(effects
				(font
					(size 1.016 1.016)
					(thickness 0.1524)
				)
			)
		)
		(property "Device Type" "R402H16"
			(at 0.064008 -5.517896 0)
			(unlocked yes)
			(layer "F.Fab")
			(hide yes)
			(effects
				(font
					(size 1.016 1.016)
					(thickness 0.1524)
				)
			)
		)
		(duplicate_pad_numbers_are_jumpers no)
		(fp_line
			(start -0.508 -0.9398)
			(end -0.508 0.9398)
			(stroke
				(width 0.1524)
				(type default)
			)
			(layer "F.SilkS")
		)
		(fp_line
			(start 0.508 -0.9398)
			(end -0.508 -0.9398)
			(stroke
				(width 0.1524)
				(type default)
			)
			(layer "F.SilkS")
		)
		(fp_rect
			(start -0.508 0.9398)
			(end 0.508 -0.9398)
			(stroke
				(width 0)
				(type default)
			)
			(fill no)
			(layer "F.CrtYd")
		)
		(fp_rect
			(start -0.508 0.9398)
			(end 0.508 -0.9398)
			(stroke
				(width 0)
				(type default)
			)
			(fill no)
			(layer "F.Fab")
		)
		(pad "1" smd custom
			(at 0 -0.4445)
			(size 0.1397 0.1397)
			(layers "F.Cu" "F.Mask" "F.Paste")
			(net "EEPROM_A2")
			(options
				(clearance outline)
				(anchor circle)
			)
			(primitives
				(gr_poly
					(pts
						(arc
							(start -0.1778 -0.2794)
							(mid -0.249642 -0.249642)
							(end -0.2794 -0.1778)
						)
						(arc
							(start -0.2794 0.1778)
							(mid -0.249642 0.249642)
							(end -0.1778 0.2794)
						)
						(arc
							(start 0.1778 0.2794)
							(mid 0.249642 0.249642)
							(end 0.2794 0.1778)
						)
						(arc
							(start 0.2794 -0.1778)
							(mid 0.249642 -0.249642)
							(end 0.1778 -0.2794)
						)
					)
					(width 0)
					(fill yes)
				)
			)
		)
		(pad "2" smd custom
			(at 0 0.4445)
			(size 0.1397 0.1397)
			(layers "F.Cu" "F.Mask" "F.Paste")
			(net "GND")
			(options
				(clearance outline)
				(anchor circle)
			)
			(primitives
				(gr_poly
					(pts
						(arc
							(start -0.1778 -0.2794)
							(mid -0.249642 -0.249642)
							(end -0.2794 -0.1778)
						)
						(arc
							(start -0.2794 0.1778)
							(mid -0.249642 0.249642)
							(end -0.1778 0.2794)
						)
						(arc
							(start 0.1778 0.2794)
							(mid 0.249642 0.249642)
							(end 0.2794 0.1778)
						)
						(arc
							(start 0.2794 -0.1778)
							(mid 0.249642 -0.249642)
							(end 0.1778 -0.2794)
						)
					)
					(width 0)
					(fill yes)
				)
			)
		)
	)
	(footprint ""
		(layer "F.Cu")
		(at 79.883 -404.114 -90)
		(property "Reference" "R555"
			(at 0 0 270)
			(layer "F.SilkS")
			(hide yes)
			(effects
				(font
					(size 1.27 1.27)
				)
			)
		)
		(property "Value" "200KR2F-L-GP"
			(at 0.064008 -3.993896 270)
			(unlocked yes)
			(layer "F.Fab")
			(hide yes)
			(effects
				(font
					(size 1.016 1.016)
					(thickness 0.1524)
				)
			)
		)
		(property "Device Type" "R402H16"
			(at 0.064008 -5.517896 270)
			(unlocked yes)
			(layer "F.Fab")
			(hide yes)
			(effects
				(font
					(size 1.016 1.016)
					(thickness 0.1524)
				)
			)
		)
		(duplicate_pad_numbers_are_jumpers no)
		(fp_line
			(start -0.508 -0.9398)
			(end -0.508 0.9398)
			(stroke
				(width 0.1524)
				(type default)
			)
			(layer "F.SilkS")
		)
		(fp_line
			(start 0.508 -0.9398)
			(end -0.508 -0.9398)
			(stroke
				(width 0.1524)
				(type default)
			)
			(layer "F.SilkS")
		)
		(fp_rect
			(start -0.508 0.9398)
			(end 0.508 -0.9398)
			(stroke
				(width 0)
				(type default)
			)
			(fill no)
			(layer "F.CrtYd")
		)
		(fp_rect
			(start -0.508 0.9398)
			(end 0.508 -0.9398)
			(stroke
				(width 0)
				(type default)
			)
			(fill no)
			(layer "F.Fab")
		)
		(pad "1" smd custom
			(at 0 -0.4445 270)
			(size 0.1397 0.1397)
			(layers "F.Cu" "F.Mask" "F.Paste")
			(net "SW_HDD6_R")
			(options
				(clearance outline)
				(anchor circle)
			)
			(primitives
				(gr_poly
					(pts
						(arc
							(start -0.1778 -0.2794)
							(mid -0.249642 -0.249642)
							(end -0.2794 -0.1778)
						)
						(arc
							(start -0.2794 0.1778)
							(mid -0.249642 0.249642)
							(end -0.1778 0.2794)
						)
						(arc
							(start 0.1778 0.2794)
							(mid 0.249642 0.249642)
							(end 0.2794 0.1778)
						)
						(arc
							(start 0.2794 -0.1778)
							(mid 0.249642 -0.249642)
							(end 0.1778 -0.2794)
						)
					)
					(width 0)
					(fill yes)
				)
			)
		)
		(pad "2" smd custom
			(at 0 0.4445 270)
			(size 0.1397 0.1397)
			(layers "F.Cu" "F.Mask" "F.Paste")
			(net "SW_HDD6_N")
			(options
				(clearance outline)
				(anchor circle)
			)
			(primitives
				(gr_poly
					(pts
						(arc
							(start -0.1778 -0.2794)
							(mid -0.249642 -0.249642)
							(end -0.2794 -0.1778)
						)
						(arc
							(start -0.2794 0.1778)
							(mid -0.249642 0.249642)
							(end -0.1778 0.2794)
						)
						(arc
							(start 0.1778 0.2794)
							(mid 0.249642 0.249642)
							(end 0.2794 0.1778)
						)
						(arc
							(start 0.2794 -0.1778)
							(mid 0.249642 -0.249642)
							(end 0.1778 -0.2794)
						)
					)
					(width 0)
					(fill yes)
				)
			)
		)
	)
	(footprint ""
		(layer "F.Cu")
		(at 12.699746 -500.1387 180)
		(property "Reference" "PR35"
			(at 0 0 180)
			(layer "F.SilkS")
			(hide yes)
			(effects
				(font
					(size 1.27 1.27)
				)
			)
		)
		(property "Value" "0R3J-0-U-GP"
			(at -0.0254 -2.5146 180)
			(unlocked yes)
			(layer "F.Fab")
			(hide yes)
			(effects
				(font
					(size 1.016 1.016)
					(thickness 0.1524)
				)
			)
		)
		(property "Device Type" "R603H22"
			(at -0.0254 -4.0386 180)
			(unlocked yes)
			(layer "F.Fab")
			(hide yes)
			(effects
				(font
					(size 1.016 1.016)
					(thickness 0.1524)
				)
			)
		)
		(duplicate_pad_numbers_are_jumpers no)
		(fp_line
			(start 0.2032 0)
			(end 0.4826 0)
			(stroke
				(width 0.2032)
				(type default)
			)
			(layer "F.SilkS")
		)
		(fp_line
			(start -0.4826 0)
			(end -0.2032 0)
			(stroke
				(width 0.2032)
				(type default)
			)
			(layer "F.SilkS")
		)
		(fp_rect
			(start -0.5842 1.3335)
			(end 0.5842 -1.3335)
			(stroke
				(width 0)
				(type default)
			)
			(fill no)
			(layer "F.CrtYd")
		)
		(fp_rect
			(start -0.5842 1.3335)
			(end 0.5842 -1.3335)
			(stroke
				(width 0)
				(type default)
			)
			(fill no)
			(layer "F.Fab")
		)
		(pad "1" smd custom
			(at 0 -0.762 180)
			(size 0.2159 0.2159)
			(layers "F.Cu" "F.Mask" "F.Paste")
			(net "P5VC_12VIN")
			(options
				(clearance outline)
				(anchor circle)
			)
			(primitives
				(gr_poly
					(pts
						(arc
							(start -0.3302 -0.4318)
							(mid -0.402042 -0.402042)
							(end -0.4318 -0.3302)
						)
						(arc
							(start -0.4318 0.3302)
							(mid -0.402042 0.402042)
							(end -0.3302 0.4318)
						)
						(arc
							(start 0.3302 0.4318)
							(mid 0.402042 0.402042)
							(end 0.4318 0.3302)
						)
						(arc
							(start 0.4318 -0.3302)
							(mid 0.402042 -0.402042)
							(end 0.3302 -0.4318)
						)
					)
					(width 0)
					(fill yes)
				)
			)
		)
		(pad "2" smd custom
			(at 0 0.762 180)
			(size 0.2159 0.2159)
			(layers "F.Cu" "F.Mask" "F.Paste")
			(net "P5VC_VDD")
			(options
				(clearance outline)
				(anchor circle)
			)
			(primitives
				(gr_poly
					(pts
						(arc
							(start -0.3302 -0.4318)
							(mid -0.402042 -0.402042)
							(end -0.4318 -0.3302)
						)
						(arc
							(start -0.4318 0.3302)
							(mid -0.402042 0.402042)
							(end -0.3302 0.4318)
						)
						(arc
							(start 0.3302 0.4318)
							(mid 0.402042 0.402042)
							(end 0.4318 0.3302)
						)
						(arc
							(start 0.4318 -0.3302)
							(mid 0.402042 -0.402042)
							(end 0.3302 -0.4318)
						)
					)
					(width 0)
					(fill yes)
				)
			)
		)
	)
	(footprint ""
		(layer "F.Cu")
		(at 68.999608 -170.999912)
		(property "Reference" "H4"
			(at 0 0 0)
			(layer "F.SilkS")
			(hide yes)
			(effects
				(font
					(size 1.27 1.27)
				)
			)
		)
		(property "Value" "HOLE315R140"
			(at 0 -7.5692 0)
			(unlocked yes)
			(layer "F.Fab")
			(hide yes)
			(effects
				(font
					(size 1.016 1.016)
					(thickness 0.1524)
				)
			)
		)
		(property "Device Type" "HOLE315R140"
			(at 0 -9.0932 0)
			(unlocked yes)
			(layer "F.Fab")
			(hide yes)
			(effects
				(font
					(size 1.016 1.016)
					(thickness 0.1524)
				)
			)
		)
		(duplicate_pad_numbers_are_jumpers no)
		(fp_poly
			(pts
				(arc
					(start 4.3053 0)
					(mid -4.3053 0)
					(end 4.3053 0)
				)
			)
			(stroke
				(width 0)
				(type default)
			)
			(fill no)
			(layer "F.CrtYd")
		)
		(fp_poly
			(pts
				(arc
					(start 4.3053 0)
					(mid -4.3053 0)
					(end 4.3053 0)
				)
			)
			(stroke
				(width 0)
				(type default)
			)
			(fill no)
			(layer "F.Fab")
		)
		(pad "1" thru_hole circle
			(at 0.00127 0.00127)
			(size 8.001 8.001)
			(drill 3.556)
			(layers "*.Cu" "*.Mask")
			(remove_unused_layers no)
			(net "GND")
			(clearance -1.7145)
			(thermal_gap 0.3048)
			(padstack
				(mode front_inner_back)
				(layer "Inner"
					(shape circle)
					(size 3.9624 3.9624)
					(clearance 0.3048)
				)
				(layer "B.Cu"
					(shape circle)
					(size 8.001 8.001)
					(clearance -1.7145)
				)
			)
		)
	)
)
